FILE_TYPE = CONNECTIVITY;
{Allegro Design Entry HDL 16.6-p007 (v16-6-112F) 10/10/2012}
"PAGE_NUMBER" = 17;
0"NC";
END.
